# S9S_MB_2U (Grand Teton) — schematic netlist excerpt (pin names and nets, part order shuffled) for the footprints in the layout excerpt that follows; sources: Cadence DE-HDL packaged netlist, KiCad conversion of 03242023_DA0F0TMBIJ0_F0T_Motherboard_J_brd_V01_OCP.brd

C2330  Q_CAP  0.1UF 25V 10% X7R  pkg 0402  page 211 : A = P3V3_9ZXL045_VDD ; B = GND
PC489_P1_8  Q_CAP  22UF 16V 20% X6S  pkg C0805  page 288 : A = SW_P12V_PVCCIN_CPU1_FLT ; B = GND
PC198_P0_2  Q_CAP  22UF 16V 20% X6S  pkg C0805  page 275 : A = SW_P12V_PVCCINFAON_CPU0_FLT ; B = GND

(kicad_pcb
	(version 20260206)
	(generator "pcbnew")
	(generator_version "10.0")
	(general
		(thickness 1.6)
		(legacy_teardrops no)
	)
	(paper "A4")
	(title_block
		(title "03242023_DA0F0TMBIJ0_F0T_Motherboard_J_brd_V01_OCP.brd")
		(comment 1 "Grand Teton / footprints 4698-4700 of 6105")
	)
	(layers
		(0 "F.Cu" signal "TOP")
		(4 "In1.Cu" signal "GND")
		(6 "In2.Cu" signal "IN1")
		(8 "In3.Cu" signal "GND1")
		(10 "In4.Cu" signal "IN2")
		(12 "In5.Cu" signal "GND2")
		(14 "In6.Cu" signal "IN3")
		(16 "In7.Cu" signal "GND3")
		(18 "In8.Cu" signal "VCC")
		(20 "In9.Cu" signal "VCC1")
		(22 "In10.Cu" signal "GND4")
		(24 "In11.Cu" signal "IN4")
		(26 "In12.Cu" signal "GND5")
		(28 "In13.Cu" signal "IN5")
		(30 "In14.Cu" signal "GND6")
		(32 "In15.Cu" signal "IN6")
		(34 "In16.Cu" signal "GND7")
		(2 "B.Cu" signal "BOTTOM")
		(9 "F.Adhes" user "F.Adhesive")
		(11 "B.Adhes" user "B.Adhesive")
		(13 "F.Paste" user "Package Geometry/Pastemask Top")
		(15 "B.Paste" user "Package Geometry/Pastemask Bottom")
		(5 "F.SilkS" user "Ref Des/Silkscreen Top")
		(7 "B.SilkS" user "Ref Des/Silkscreen Bottom")
		(1 "F.Mask" user "Board Geometry/Soldermask Top")
		(3 "B.Mask" user "Board Geometry/Soldermask Bottom")
		(17 "Dwgs.User" user "User.Drawings")
		(19 "Cmts.User" user "User.Comments")
		(21 "Eco1.User" user "User.Eco1")
		(23 "Eco2.User" user "User.Eco2")
		(25 "Edge.Cuts" user "Board Geometry/Outline")
		(27 "Margin" user)
		(31 "F.CrtYd" user "Package Geometry/Place Bound Top")
		(29 "B.CrtYd" user "Package Geometry/Place Bound Bottom")
		(35 "F.Fab" user "Ref Des/Assembly Top")
		(33 "B.Fab" user "Ref Des/Assembly Bottom")
	)
	(footprint ""
		(layer "B.Cu")
		(at 110.31855 -413.110426 180)
		(property "Reference" "C2330"
			(at 0 0 0)
			(layer "B.SilkS")
			(hide yes)
			(effects
				(font
					(size 1.27 1.27)
				)
				(justify mirror)
			)
		)
		(property "Value" ""
			(at 0 0 0)
			(layer "B.Fab")
			(effects
				(font
					(size 1.27 1.27)
				)
				(justify mirror)
			)
		)
		(duplicate_pad_numbers_are_jumpers no)
		(fp_line
			(start 0.7874 0.4064)
			(end 0.7874 -0.4064)
			(stroke
				(width 0.1524)
				(type default)
			)
			(layer "B.SilkS")
		)
		(fp_line
			(start 0.7874 -0.4064)
			(end -0.7874 -0.4064)
			(stroke
				(width 0.1524)
				(type default)
			)
			(layer "B.SilkS")
		)
		(fp_line
			(start -0.7874 0.4064)
			(end 0.7874 0.4064)
			(stroke
				(width 0.1524)
				(type default)
			)
			(layer "B.SilkS")
		)
		(fp_line
			(start -0.7874 -0.4064)
			(end -0.7874 0.4064)
			(stroke
				(width 0.1524)
				(type default)
			)
			(layer "B.SilkS")
		)
		(fp_line
			(start 0.67945 0.3048)
			(end 0.67945 -0.305054)
			(stroke
				(width 0.1)
				(type default)
			)
			(layer "B.Fab")
		)
		(fp_line
			(start 0.67945 -0.305054)
			(end 0.12065 -0.305054)
			(stroke
				(width 0.1)
				(type default)
			)
			(layer "B.Fab")
		)
		(fp_line
			(start 0.12065 0.3048)
			(end 0.67945 0.3048)
			(stroke
				(width 0.1)
				(type default)
			)
			(layer "B.Fab")
		)
		(fp_line
			(start 0.12065 0.2794)
			(end 0.12065 0.3048)
			(stroke
				(width 0.1)
				(type default)
			)
			(layer "B.Fab")
		)
		(fp_line
			(start 0.12065 -0.2794)
			(end -0.12065 -0.2794)
			(stroke
				(width 0.1)
				(type default)
			)
			(layer "B.Fab")
		)
		(fp_line
			(start 0.12065 -0.305054)
			(end 0.12065 -0.2794)
			(stroke
				(width 0.1)
				(type default)
			)
			(layer "B.Fab")
		)
		(fp_line
			(start -0.120396 0.3048)
			(end -0.120396 0.2794)
			(stroke
				(width 0.1)
				(type default)
			)
			(layer "B.Fab")
		)
		(fp_line
			(start -0.120396 0.2794)
			(end 0.12065 0.2794)
			(stroke
				(width 0.1)
				(type default)
			)
			(layer "B.Fab")
		)
		(fp_line
			(start -0.12065 -0.2794)
			(end -0.12065 -0.3048)
			(stroke
				(width 0.1)
				(type default)
			)
			(layer "B.Fab")
		)
		(fp_line
			(start -0.12065 -0.3048)
			(end -0.67945 -0.3048)
			(stroke
				(width 0.1)
				(type default)
			)
			(layer "B.Fab")
		)
		(fp_line
			(start -0.67945 0.3048)
			(end -0.120396 0.3048)
			(stroke
				(width 0.1)
				(type default)
			)
			(layer "B.Fab")
		)
		(fp_line
			(start -0.67945 -0.3048)
			(end -0.67945 0.3048)
			(stroke
				(width 0.1)
				(type default)
			)
			(layer "B.Fab")
		)
		(pad "1" smd circle
			(at 0.40005 0)
			(size 0 0)
			(layers "B.Cu" "B.Mask" "B.Paste")
			(net "P3V3_9ZXL045_VDD")
		)
		(pad "2" smd circle
			(at -0.40005 0)
			(size 0 0)
			(layers "B.Cu" "B.Mask" "B.Paste")
			(net "GND")
		)
	)
	(footprint ""
		(layer "B.Cu")
		(at 138.921998 -342.936576 90)
		(property "Reference" "PC489_P1_8"
			(at 0 0 90)
			(layer "B.SilkS")
			(hide yes)
			(effects
				(font
					(size 1.27 1.27)
				)
				(justify mirror)
			)
		)
		(property "Value" ""
			(at 0 0 90)
			(layer "B.Fab")
			(effects
				(font
					(size 1.27 1.27)
				)
				(justify mirror)
			)
		)
		(duplicate_pad_numbers_are_jumpers no)
		(fp_line
			(start 1.524 -0.762)
			(end -1.524 -0.762)
			(stroke
				(width 0.1524)
				(type default)
			)
			(layer "B.SilkS")
		)
		(fp_line
			(start -1.524 -0.762)
			(end -1.524 0.762)
			(stroke
				(width 0.1524)
				(type default)
			)
			(layer "B.SilkS")
		)
		(fp_line
			(start 1.524 0.762)
			(end 1.524 -0.762)
			(stroke
				(width 0.1524)
				(type default)
			)
			(layer "B.SilkS")
		)
		(fp_line
			(start -1.524 0.762)
			(end 1.524 0.762)
			(stroke
				(width 0.1524)
				(type default)
			)
			(layer "B.SilkS")
		)
		(fp_line
			(start 1.1049 -0.724916)
			(end 1.1049 0.724916)
			(stroke
				(width 0.1)
				(type default)
			)
			(layer "B.Fab")
		)
		(fp_line
			(start -1.1049 -0.724916)
			(end 1.1049 -0.724916)
			(stroke
				(width 0.1)
				(type default)
			)
			(layer "B.Fab")
		)
		(fp_line
			(start 1.1049 0.724916)
			(end -1.1049 0.724916)
			(stroke
				(width 0.1)
				(type default)
			)
			(layer "B.Fab")
		)
		(fp_line
			(start -1.1049 0.724916)
			(end -1.1049 -0.724916)
			(stroke
				(width 0.1)
				(type default)
			)
			(layer "B.Fab")
		)
		(pad "1" smd rect
			(at 0.889 0 90)
			(size 1.016 1.27)
			(layers "B.Cu" "B.Mask" "B.Paste")
			(net "SW_P12V_PVCCIN_CPU1_FLT")
		)
		(pad "2" smd rect
			(at -0.889 0 90)
			(size 1.016 1.27)
			(layers "B.Cu" "B.Mask" "B.Paste")
			(net "GND")
		)
	)
	(footprint ""
		(layer "B.Cu")
		(at 416.02914 -178.336194)
		(property "Reference" "PC198_P0_2"
			(at 0 0 0)
			(layer "B.SilkS")
			(hide yes)
			(effects
				(font
					(size 1.27 1.27)
				)
				(justify mirror)
			)
		)
		(property "Value" ""
			(at 0 0 0)
			(layer "B.Fab")
			(effects
				(font
					(size 1.27 1.27)
				)
				(justify mirror)
			)
		)
		(duplicate_pad_numbers_are_jumpers no)
		(fp_line
			(start -1.524 -0.762)
			(end -1.524 0.762)
			(stroke
				(width 0.1524)
				(type default)
			)
			(layer "B.SilkS")
		)
		(fp_line
			(start -1.524 0.762)
			(end 1.524 0.762)
			(stroke
				(width 0.1524)
				(type default)
			)
			(layer "B.SilkS")
		)
		(fp_line
			(start 1.524 -0.762)
			(end -1.524 -0.762)
			(stroke
				(width 0.1524)
				(type default)
			)
			(layer "B.SilkS")
		)
		(fp_line
			(start 1.524 0.762)
			(end 1.524 -0.762)
			(stroke
				(width 0.1524)
				(type default)
			)
			(layer "B.SilkS")
		)
		(fp_line
			(start -1.1049 -0.724916)
			(end 1.1049 -0.724916)
			(stroke
				(width 0.1)
				(type default)
			)
			(layer "B.Fab")
		)
		(fp_line
			(start -1.1049 0.724916)
			(end -1.1049 -0.724916)
			(stroke
				(width 0.1)
				(type default)
			)
			(layer "B.Fab")
		)
		(fp_line
			(start 1.1049 -0.724916)
			(end 1.1049 0.724916)
			(stroke
				(width 0.1)
				(type default)
			)
			(layer "B.Fab")
		)
		(fp_line
			(start 1.1049 0.724916)
			(end -1.1049 0.724916)
			(stroke
				(width 0.1)
				(type default)
			)
			(layer "B.Fab")
		)
		(pad "1" smd rect
			(at 0.889 0)
			(size 1.016 1.27)
			(layers "B.Cu" "B.Mask" "B.Paste")
			(net "SW_P12V_PVCCINFAON_CPU0_FLT")
		)
		(pad "2" smd rect
			(at -0.889 0)
			(size 1.016 1.27)
			(layers "B.Cu" "B.Mask" "B.Paste")
			(net "GND")
		)
	)
)
